# S9S_MB_2U (Grand Teton) — schematic netlist excerpt (pin names and nets, part order shuffled) for the footprints in the layout excerpt that follows; sources: Cadence DE-HDL packaged netlist, KiCad conversion of 03242023_DA0F0TMBIJ0_F0T_Motherboard_J_brd_V01_OCP.brd

C915  Q_CAP_DIFFBUS  DIFF BUS_0.22UF 6.3V 20% X6S  pkg C0201  page 173 : \1\ = P5E_CPU0_PE0_TX_C_DP<9> ; \2\ = P5E_CPU0_PE0_TX_DP<9>
R804  Q_RES  33.2 1% CHIP  pkg 0402LF  page 221 : A = JTAG_PLD_TDO_R ; B = JTAG_BMC_PLD_TDO
R3032  Q_RES  100K 1% EMPTY  pkg 0402LF  page 148 : A = FM_SMB_2_ALERT_GPU_N ; B = GND

(kicad_pcb
	(version 20260206)
	(generator "pcbnew")
	(generator_version "10.0")
	(general
		(thickness 1.6)
		(legacy_teardrops no)
	)
	(paper "A4")
	(title_block
		(title "03242023_DA0F0TMBIJ0_F0T_Motherboard_J_brd_V01_OCP.brd")
		(comment 1 "Grand Teton / footprints 2686-2688 of 6105")
	)
	(layers
		(0 "F.Cu" signal "TOP")
		(4 "In1.Cu" signal "GND")
		(6 "In2.Cu" signal "IN1")
		(8 "In3.Cu" signal "GND1")
		(10 "In4.Cu" signal "IN2")
		(12 "In5.Cu" signal "GND2")
		(14 "In6.Cu" signal "IN3")
		(16 "In7.Cu" signal "GND3")
		(18 "In8.Cu" signal "VCC")
		(20 "In9.Cu" signal "VCC1")
		(22 "In10.Cu" signal "GND4")
		(24 "In11.Cu" signal "IN4")
		(26 "In12.Cu" signal "GND5")
		(28 "In13.Cu" signal "IN5")
		(30 "In14.Cu" signal "GND6")
		(32 "In15.Cu" signal "IN6")
		(34 "In16.Cu" signal "GND7")
		(2 "B.Cu" signal "BOTTOM")
		(9 "F.Adhes" user "F.Adhesive")
		(11 "B.Adhes" user "B.Adhesive")
		(13 "F.Paste" user "Package Geometry/Pastemask Top")
		(15 "B.Paste" user "Package Geometry/Pastemask Bottom")
		(5 "F.SilkS" user "Ref Des/Silkscreen Top")
		(7 "B.SilkS" user "Ref Des/Silkscreen Bottom")
		(1 "F.Mask" user "Board Geometry/Soldermask Top")
		(3 "B.Mask" user "Board Geometry/Soldermask Bottom")
		(17 "Dwgs.User" user "User.Drawings")
		(19 "Cmts.User" user "User.Comments")
		(21 "Eco1.User" user "User.Eco1")
		(23 "Eco2.User" user "User.Eco2")
		(25 "Edge.Cuts" user "Board Geometry/Outline")
		(27 "Margin" user)
		(31 "F.CrtYd" user "Package Geometry/Place Bound Top")
		(29 "B.CrtYd" user "Package Geometry/Place Bound Bottom")
		(35 "F.Fab" user "Ref Des/Assembly Top")
		(33 "B.Fab" user "Ref Des/Assembly Bottom")
	)
	(footprint ""
		(layer "F.Cu")
		(at 131.014216 -66.919602 90)
		(property "Reference" "R804"
			(at 0 0 90)
			(layer "F.SilkS")
			(hide yes)
			(effects
				(font
					(size 1.27 1.27)
				)
			)
		)
		(property "Value" ""
			(at 0 0 90)
			(layer "F.Fab")
			(effects
				(font
					(size 1.27 1.27)
				)
			)
		)
		(duplicate_pad_numbers_are_jumpers no)
		(fp_line
			(start 0.7874 -0.4064)
			(end 0.7874 0.4064)
			(stroke
				(width 0.1524)
				(type default)
			)
			(layer "F.SilkS")
		)
		(fp_line
			(start -0.7874 -0.4064)
			(end 0.7874 -0.4064)
			(stroke
				(width 0.1524)
				(type default)
			)
			(layer "F.SilkS")
		)
		(fp_line
			(start 0.7874 0.4064)
			(end -0.7874 0.4064)
			(stroke
				(width 0.1524)
				(type default)
			)
			(layer "F.SilkS")
		)
		(fp_line
			(start -0.7874 0.4064)
			(end -0.7874 -0.4064)
			(stroke
				(width 0.1524)
				(type default)
			)
			(layer "F.SilkS")
		)
		(fp_line
			(start -0.12065 -0.305054)
			(end -0.12065 -0.2794)
			(stroke
				(width 0.1)
				(type default)
			)
			(layer "F.Fab")
		)
		(fp_line
			(start -0.67945 -0.305054)
			(end -0.12065 -0.305054)
			(stroke
				(width 0.1)
				(type default)
			)
			(layer "F.Fab")
		)
		(fp_line
			(start 0.67945 -0.3048)
			(end 0.67945 0.3048)
			(stroke
				(width 0.1)
				(type default)
			)
			(layer "F.Fab")
		)
		(fp_line
			(start 0.12065 -0.3048)
			(end 0.67945 -0.3048)
			(stroke
				(width 0.1)
				(type default)
			)
			(layer "F.Fab")
		)
		(fp_line
			(start 0.12065 -0.2794)
			(end 0.12065 -0.3048)
			(stroke
				(width 0.1)
				(type default)
			)
			(layer "F.Fab")
		)
		(fp_line
			(start -0.12065 -0.2794)
			(end 0.12065 -0.2794)
			(stroke
				(width 0.1)
				(type default)
			)
			(layer "F.Fab")
		)
		(fp_line
			(start 0.120396 0.2794)
			(end -0.12065 0.2794)
			(stroke
				(width 0.1)
				(type default)
			)
			(layer "F.Fab")
		)
		(fp_line
			(start -0.12065 0.2794)
			(end -0.12065 0.3048)
			(stroke
				(width 0.1)
				(type default)
			)
			(layer "F.Fab")
		)
		(fp_line
			(start 0.67945 0.3048)
			(end 0.120396 0.3048)
			(stroke
				(width 0.1)
				(type default)
			)
			(layer "F.Fab")
		)
		(fp_line
			(start 0.120396 0.3048)
			(end 0.120396 0.2794)
			(stroke
				(width 0.1)
				(type default)
			)
			(layer "F.Fab")
		)
		(fp_line
			(start -0.12065 0.3048)
			(end -0.67945 0.3048)
			(stroke
				(width 0.1)
				(type default)
			)
			(layer "F.Fab")
		)
		(fp_line
			(start -0.67945 0.3048)
			(end -0.67945 -0.305054)
			(stroke
				(width 0.1)
				(type default)
			)
			(layer "F.Fab")
		)
		(pad "1" smd circle
			(at -0.40005 0 90)
			(size 0 0)
			(layers "F.Cu" "F.Mask" "F.Paste")
			(net "JTAG_PLD_TDO_R")
		)
		(pad "2" smd circle
			(at 0.40005 0 90)
			(size 0 0)
			(layers "F.Cu" "F.Mask" "F.Paste")
			(net "JTAG_BMC_PLD_TDO")
		)
	)
	(footprint ""
		(layer "F.Cu")
		(at 114.30508 -397.874998 90)
		(property "Reference" "R3032"
			(at 0 0 90)
			(layer "F.SilkS")
			(hide yes)
			(effects
				(font
					(size 1.27 1.27)
				)
			)
		)
		(property "Value" ""
			(at 0 0 90)
			(layer "F.Fab")
			(effects
				(font
					(size 1.27 1.27)
				)
			)
		)
		(duplicate_pad_numbers_are_jumpers no)
		(fp_line
			(start 0.7874 -0.4064)
			(end 0.7874 0.4064)
			(stroke
				(width 0.1524)
				(type default)
			)
			(layer "F.SilkS")
		)
		(fp_line
			(start -0.7874 -0.4064)
			(end 0.7874 -0.4064)
			(stroke
				(width 0.1524)
				(type default)
			)
			(layer "F.SilkS")
		)
		(fp_line
			(start 0.7874 0.4064)
			(end -0.7874 0.4064)
			(stroke
				(width 0.1524)
				(type default)
			)
			(layer "F.SilkS")
		)
		(fp_line
			(start -0.7874 0.4064)
			(end -0.7874 -0.4064)
			(stroke
				(width 0.1524)
				(type default)
			)
			(layer "F.SilkS")
		)
		(fp_line
			(start -0.12065 -0.305054)
			(end -0.12065 -0.2794)
			(stroke
				(width 0.1)
				(type default)
			)
			(layer "F.Fab")
		)
		(fp_line
			(start -0.67945 -0.305054)
			(end -0.12065 -0.305054)
			(stroke
				(width 0.1)
				(type default)
			)
			(layer "F.Fab")
		)
		(fp_line
			(start 0.67945 -0.3048)
			(end 0.67945 0.3048)
			(stroke
				(width 0.1)
				(type default)
			)
			(layer "F.Fab")
		)
		(fp_line
			(start 0.12065 -0.3048)
			(end 0.67945 -0.3048)
			(stroke
				(width 0.1)
				(type default)
			)
			(layer "F.Fab")
		)
		(fp_line
			(start 0.12065 -0.2794)
			(end 0.12065 -0.3048)
			(stroke
				(width 0.1)
				(type default)
			)
			(layer "F.Fab")
		)
		(fp_line
			(start -0.12065 -0.2794)
			(end 0.12065 -0.2794)
			(stroke
				(width 0.1)
				(type default)
			)
			(layer "F.Fab")
		)
		(fp_line
			(start 0.120396 0.2794)
			(end -0.12065 0.2794)
			(stroke
				(width 0.1)
				(type default)
			)
			(layer "F.Fab")
		)
		(fp_line
			(start -0.12065 0.2794)
			(end -0.12065 0.3048)
			(stroke
				(width 0.1)
				(type default)
			)
			(layer "F.Fab")
		)
		(fp_line
			(start 0.67945 0.3048)
			(end 0.120396 0.3048)
			(stroke
				(width 0.1)
				(type default)
			)
			(layer "F.Fab")
		)
		(fp_line
			(start 0.120396 0.3048)
			(end 0.120396 0.2794)
			(stroke
				(width 0.1)
				(type default)
			)
			(layer "F.Fab")
		)
		(fp_line
			(start -0.12065 0.3048)
			(end -0.67945 0.3048)
			(stroke
				(width 0.1)
				(type default)
			)
			(layer "F.Fab")
		)
		(fp_line
			(start -0.67945 0.3048)
			(end -0.67945 -0.305054)
			(stroke
				(width 0.1)
				(type default)
			)
			(layer "F.Fab")
		)
		(pad "1" smd circle
			(at -0.40005 0 90)
			(size 0 0)
			(layers "F.Cu" "F.Mask" "F.Paste")
			(net "FM_SMB_2_ALERT_GPU_N")
		)
		(pad "2" smd circle
			(at 0.40005 0 90)
			(size 0 0)
			(layers "F.Cu" "F.Mask" "F.Paste")
			(net "GND")
		)
	)
	(footprint ""
		(layer "F.Cu")
		(at 324.594728 -408.517344 -90)
		(property "Reference" "C915"
			(at 0 0 270)
			(layer "F.SilkS")
			(hide yes)
			(effects
				(font
					(size 1.27 1.27)
				)
			)
		)
		(property "Value" ""
			(at 0 0 270)
			(layer "F.Fab")
			(effects
				(font
					(size 1.27 1.27)
				)
			)
		)
		(duplicate_pad_numbers_are_jumpers no)
		(fp_line
			(start -0.299974 0.150114)
			(end -0.299974 -0.150114)
			(stroke
				(width 0.1)
				(type default)
			)
			(layer "F.Fab")
		)
		(fp_line
			(start 0.299974 0.150114)
			(end -0.299974 0.150114)
			(stroke
				(width 0.1)
				(type default)
			)
			(layer "F.Fab")
		)
		(fp_line
			(start -0.299974 -0.150114)
			(end 0.299974 -0.150114)
			(stroke
				(width 0.1)
				(type default)
			)
			(layer "F.Fab")
		)
		(fp_line
			(start 0.299974 -0.150114)
			(end 0.299974 0.150114)
			(stroke
				(width 0.1)
				(type default)
			)
			(layer "F.Fab")
		)
		(pad "1" smd rect
			(at -0.2667 0 270)
			(size 0.3048 0.381)
			(layers "F.Cu" "F.Mask" "F.Paste")
			(net "P5E_CPU0_PE0_TX_C_DP<9>")
		)
		(pad "2" smd rect
			(at 0.2667 0 270)
			(size 0.3048 0.381)
			(layers "F.Cu" "F.Mask" "F.Paste")
			(net "P5E_CPU0_PE0_TX_DP<9>")
		)
	)
)
